# T6G (Grand Teton) — schematic netlist excerpt (pin names and nets, part order shuffled) for the footprints in the layout excerpt that follows; sources: Cadence DE-HDL packaged netlist, KiCad conversion of 04192023_DAF0TMB3IC0_F0TG_MB_C_brd_V02_OCP.brd

C1027  Q_CAP  1UF 4V 20% X6S  pkg 0201  page 312 : A = P0V9_CPU0_RT3_2A ; B = GND

DB11  TDR_3P  EMPTY  pkg TH2  page 260
  GND  = T1_GND
  IO1  = TDR_SE_50_OHM_IN4
  IO2  = TDR_SE_50_OHM_IN4

C2524  Q_CAP  22UF 4V 20% X6S  pkg C0402  page 71 : A = PVDD18_S5_P0 ; B = GND

(kicad_pcb
	(version 20260206)
	(generator "pcbnew")
	(generator_version "10.0")
	(general
		(thickness 1.6)
		(legacy_teardrops no)
	)
	(paper "A4")
	(title_block
		(title "04192023_DAF0TMB3IC0_F0TG_MB_C_brd_V02_OCP.brd")
		(comment 1 "Grand Teton / footprints 5953-5955 of 8354")
	)
	(layers
		(0 "F.Cu" signal "TOP")
		(4 "In1.Cu" signal "GND")
		(6 "In2.Cu" signal "IN1")
		(8 "In3.Cu" signal "GND1")
		(10 "In4.Cu" signal "IN2")
		(12 "In5.Cu" signal "GND2")
		(14 "In6.Cu" signal "IN3")
		(16 "In7.Cu" signal "GND3")
		(18 "In8.Cu" signal "VCC")
		(20 "In9.Cu" signal "VCC1")
		(22 "In10.Cu" signal "GND4")
		(24 "In11.Cu" signal "IN4")
		(26 "In12.Cu" signal "GND5")
		(28 "In13.Cu" signal "IN5")
		(30 "In14.Cu" signal "GND6")
		(32 "In15.Cu" signal "IN6")
		(34 "In16.Cu" signal "GND7")
		(2 "B.Cu" signal "BOTTOM")
		(9 "F.Adhes" user "F.Adhesive")
		(11 "B.Adhes" user "B.Adhesive")
		(13 "F.Paste" user "Package Geometry/Pastemask Top")
		(15 "B.Paste" user "Package Geometry/Pastemask Bottom")
		(5 "F.SilkS" user "Ref Des/Silkscreen Top")
		(7 "B.SilkS" user "Ref Des/Silkscreen Bottom")
		(1 "F.Mask" user "Board Geometry/Soldermask Top")
		(3 "B.Mask" user "Board Geometry/Soldermask Bottom")
		(17 "Dwgs.User" user "User.Drawings")
		(19 "Cmts.User" user "User.Comments")
		(21 "Eco1.User" user "User.Eco1")
		(23 "Eco2.User" user "User.Eco2")
		(25 "Edge.Cuts" user "Board Geometry/Outline")
		(27 "Margin" user)
		(31 "F.CrtYd" user "Package Geometry/Place Bound Top")
		(29 "B.CrtYd" user "Package Geometry/Place Bound Bottom")
		(35 "F.Fab" user "Ref Des/Assembly Top")
		(33 "B.Fab" user "Ref Des/Assembly Bottom")
	)
	(footprint ""
		(layer "B.Cu")
		(at 479.088958 -437.516778 180)
		(property "Reference" "DB11"
			(at 2.581402 -8.320786 270)
			(unlocked yes)
			(layer "B.SilkS")
			(effects
				(font
					(size 0.7874 0.5842)
					(thickness 0.1524)
				)
				(justify left mirror)
			)
		)
		(property "Value" ""
			(at 0 0 0)
			(layer "B.Fab")
			(effects
				(font
					(size 1.27 1.27)
				)
				(justify mirror)
			)
		)
		(duplicate_pad_numbers_are_jumpers no)
		(fp_line
			(start 3.330702 -4.771136)
			(end -3.330702 -4.771136)
			(stroke
				(width 0.1524)
				(type default)
			)
			(layer "B.SilkS")
		)
		(fp_line
			(start 0 4.011168)
			(end 3.330702 -4.771136)
			(stroke
				(width 0.1524)
				(type default)
			)
			(layer "B.SilkS")
		)
		(fp_line
			(start -3.330702 -4.771136)
			(end 0 4.011168)
			(stroke
				(width 0.1524)
				(type default)
			)
			(layer "B.SilkS")
		)
		(fp_line
			(start 3.330702 -4.771136)
			(end -3.330702 -4.771136)
			(stroke
				(width 0.1)
				(type default)
			)
			(layer "B.Fab")
		)
		(fp_line
			(start 0 4.011168)
			(end 3.330702 -4.771136)
			(stroke
				(width 0.1)
				(type default)
			)
			(layer "B.Fab")
		)
		(fp_line
			(start -3.330702 -4.771136)
			(end 0 4.011168)
			(stroke
				(width 0.1)
				(type default)
			)
			(layer "B.Fab")
		)
		(pad "1" thru_hole circle
			(at 0 0)
			(size 2.159 2.159)
			(drill 1.7018)
			(layers "*.Cu" "*.Mask")
			(remove_unused_layers no)
			(net "T1_GND")
			(clearance 0.0254)
			(thermal_gap 0.0254)
		)
		(pad "2" thru_hole circle
			(at 1.27 -3.348736)
			(size 2.159 2.159)
			(drill 1.7018)
			(layers "*.Cu" "*.Mask")
			(remove_unused_layers no)
			(net "TDR_SE_50_OHM_IN4")
			(clearance 0.0254)
			(thermal_gap 0.0254)
		)
		(pad "3" thru_hole circle
			(at -1.27 -3.348736)
			(size 2.159 2.159)
			(drill 1.7018)
			(layers "*.Cu" "*.Mask")
			(remove_unused_layers no)
			(net "TDR_SE_50_OHM_IN4")
			(clearance 0.0254)
			(thermal_gap 0.0254)
		)
	)
	(footprint ""
		(layer "B.Cu")
		(at 347.040454 -255.84531 180)
		(property "Reference" "C2524"
			(at 0 0 0)
			(layer "B.SilkS")
			(hide yes)
			(effects
				(font
					(size 1.27 1.27)
				)
				(justify mirror)
			)
		)
		(property "Value" ""
			(at 0 0 0)
			(layer "B.Fab")
			(effects
				(font
					(size 1.27 1.27)
				)
				(justify mirror)
			)
		)
		(duplicate_pad_numbers_are_jumpers no)
		(fp_line
			(start 0.7874 0.4064)
			(end 0.7874 -0.4064)
			(stroke
				(width 0.1524)
				(type default)
			)
			(layer "B.SilkS")
		)
		(fp_line
			(start 0.7874 -0.4064)
			(end -0.7874 -0.4064)
			(stroke
				(width 0.1524)
				(type default)
			)
			(layer "B.SilkS")
		)
		(fp_line
			(start -0.7874 0.4064)
			(end 0.7874 0.4064)
			(stroke
				(width 0.1524)
				(type default)
			)
			(layer "B.SilkS")
		)
		(fp_line
			(start -0.7874 -0.4064)
			(end -0.7874 0.4064)
			(stroke
				(width 0.1524)
				(type default)
			)
			(layer "B.SilkS")
		)
		(fp_line
			(start 0.67945 0.3048)
			(end 0.67945 -0.305054)
			(stroke
				(width 0.1)
				(type default)
			)
			(layer "B.Fab")
		)
		(fp_line
			(start 0.67945 -0.305054)
			(end 0.12065 -0.305054)
			(stroke
				(width 0.1)
				(type default)
			)
			(layer "B.Fab")
		)
		(fp_line
			(start 0.12065 0.3048)
			(end 0.67945 0.3048)
			(stroke
				(width 0.1)
				(type default)
			)
			(layer "B.Fab")
		)
		(fp_line
			(start 0.12065 0.2794)
			(end 0.12065 0.3048)
			(stroke
				(width 0.1)
				(type default)
			)
			(layer "B.Fab")
		)
		(fp_line
			(start 0.12065 -0.2794)
			(end -0.12065 -0.2794)
			(stroke
				(width 0.1)
				(type default)
			)
			(layer "B.Fab")
		)
		(fp_line
			(start 0.12065 -0.305054)
			(end 0.12065 -0.2794)
			(stroke
				(width 0.1)
				(type default)
			)
			(layer "B.Fab")
		)
		(fp_line
			(start -0.120396 0.3048)
			(end -0.120396 0.2794)
			(stroke
				(width 0.1)
				(type default)
			)
			(layer "B.Fab")
		)
		(fp_line
			(start -0.120396 0.2794)
			(end 0.12065 0.2794)
			(stroke
				(width 0.1)
				(type default)
			)
			(layer "B.Fab")
		)
		(fp_line
			(start -0.12065 -0.2794)
			(end -0.12065 -0.3048)
			(stroke
				(width 0.1)
				(type default)
			)
			(layer "B.Fab")
		)
		(fp_line
			(start -0.12065 -0.3048)
			(end -0.67945 -0.3048)
			(stroke
				(width 0.1)
				(type default)
			)
			(layer "B.Fab")
		)
		(fp_line
			(start -0.67945 0.3048)
			(end -0.120396 0.3048)
			(stroke
				(width 0.1)
				(type default)
			)
			(layer "B.Fab")
		)
		(fp_line
			(start -0.67945 -0.3048)
			(end -0.67945 0.3048)
			(stroke
				(width 0.1)
				(type default)
			)
			(layer "B.Fab")
		)
		(pad "1" smd circle
			(at 0.40005 0)
			(size 0 0)
			(layers "B.Cu" "B.Mask" "B.Paste")
			(net "PVDD18_S5_P0")
		)
		(pad "2" smd circle
			(at -0.40005 0)
			(size 0 0)
			(layers "B.Cu" "B.Mask" "B.Paste")
			(net "GND")
		)
	)
	(footprint ""
		(layer "B.Cu")
		(at 387.278626 -395.148562 90)
		(property "Reference" "C1027"
			(at 0 0 90)
			(layer "B.SilkS")
			(hide yes)
			(effects
				(font
					(size 1.27 1.27)
				)
				(justify mirror)
			)
		)
		(property "Value" ""
			(at 0 0 90)
			(layer "B.Fab")
			(effects
				(font
					(size 1.27 1.27)
				)
				(justify mirror)
			)
		)
		(duplicate_pad_numbers_are_jumpers no)
		(fp_line
			(start 0.299974 -0.150114)
			(end -0.299974 -0.150114)
			(stroke
				(width 0.1)
				(type default)
			)
			(layer "B.Fab")
		)
		(fp_line
			(start -0.299974 -0.150114)
			(end -0.299974 0.150114)
			(stroke
				(width 0.1)
				(type default)
			)
			(layer "B.Fab")
		)
		(fp_line
			(start 0.299974 0.150114)
			(end 0.299974 -0.150114)
			(stroke
				(width 0.1)
				(type default)
			)
			(layer "B.Fab")
		)
		(fp_line
			(start -0.299974 0.150114)
			(end 0.299974 0.150114)
			(stroke
				(width 0.1)
				(type default)
			)
			(layer "B.Fab")
		)
		(pad "1" smd rect
			(at 0.2667 0 270)
			(size 0.3048 0.381)
			(layers "B.Cu" "B.Mask" "B.Paste")
			(net "P0V9_CPU0_RT3_2A")
		)
		(pad "2" smd rect
			(at -0.2667 0 270)
			(size 0.3048 0.381)
			(layers "B.Cu" "B.Mask" "B.Paste")
			(net "GND")
		)
	)
)
